(kicad_pcb
	(version 20260206)
	(generator "pcbnew")
	(generator_version "10.0")
	(general
		(thickness 1.6)
		(legacy_teardrops no)
	)
	(paper "A4")
	(title_block
		(title "01162023_DA0F0TEBIF0_F0T_Expander_BD_F_brd_V02_OCP.brd")
		(comment 1 "Grand Teton / footprints 9577-9584 of 9728")
	)
	(layers
		(0 "F.Cu" signal "TOP")
		(4 "In1.Cu" signal "GND")
		(6 "In2.Cu" signal "VCC")
		(8 "In3.Cu" signal "VCC1")
		(10 "In4.Cu" signal "GND1")
		(12 "In5.Cu" signal "IN1")
		(14 "In6.Cu" signal "GND2")
		(16 "In7.Cu" signal "IN2")
		(18 "In8.Cu" signal "GND3")
		(20 "In9.Cu" signal "IN3")
		(22 "In10.Cu" signal "GND4")
		(24 "In11.Cu" signal "IN4")
		(26 "In12.Cu" signal "GND5")
		(28 "In13.Cu" signal "IN5")
		(30 "In14.Cu" signal "GND6")
		(32 "In15.Cu" signal "IN6")
		(34 "In16.Cu" signal "GND7")
		(2 "B.Cu" signal "BOTTOM")
		(9 "F.Adhes" user "F.Adhesive")
		(11 "B.Adhes" user "B.Adhesive")
		(13 "F.Paste" user "Package Geometry/Pastemask Top")
		(15 "B.Paste" user "Package Geometry/Pastemask Bottom")
		(5 "F.SilkS" user "Ref Des/Silkscreen Top")
		(7 "B.SilkS" user "Ref Des/Silkscreen Bottom")
		(1 "F.Mask" user "Board Geometry/Soldermask Top")
		(3 "B.Mask" user "Board Geometry/Soldermask Bottom")
		(17 "Dwgs.User" user "User.Drawings")
		(19 "Cmts.User" user "User.Comments")
		(21 "Eco1.User" user "User.Eco1")
		(23 "Eco2.User" user "User.Eco2")
		(25 "Edge.Cuts" user "Board Geometry/Outline")
		(27 "Margin" user)
		(31 "F.CrtYd" user "Package Geometry/Place Bound Top")
		(29 "B.CrtYd" user "Package Geometry/Place Bound Bottom")
		(35 "F.Fab" user "Ref Des/Assembly Top")
		(33 "B.Fab" user "Ref Des/Assembly Bottom")
	)
	(footprint ""
		(layer "B.Cu")
		(at 297.549824 -301.599854 -90)
		(property "Reference" "C1679"
			(at 0 0 90)
			(layer "B.SilkS")
			(hide yes)
			(effects
				(font
					(size 1.27 1.27)
				)
				(justify mirror)
			)
		)
		(property "Value" ""
			(at 0 0 90)
			(layer "B.Fab")
			(effects
				(font
					(size 1.27 1.27)
				)
				(justify mirror)
			)
		)
		(duplicate_pad_numbers_are_jumpers no)
		(fp_line
			(start -0.299974 0.150114)
			(end 0.299974 0.150114)
			(stroke
				(width 0.1)
				(type default)
			)
			(layer "B.Fab")
		)
		(fp_line
			(start 0.299974 0.150114)
			(end 0.299974 -0.150114)
			(stroke
				(width 0.1)
				(type default)
			)
			(layer "B.Fab")
		)
		(fp_line
			(start -0.299974 -0.150114)
			(end -0.299974 0.150114)
			(stroke
				(width 0.1)
				(type default)
			)
			(layer "B.Fab")
		)
		(fp_line
			(start 0.299974 -0.150114)
			(end -0.299974 -0.150114)
			(stroke
				(width 0.1)
				(type default)
			)
			(layer "B.Fab")
		)
		(pad "1" smd rect
			(at 0.2667 0 90)
			(size 0.3048 0.381)
			(layers "B.Cu" "B.Mask" "B.Paste")
			(net "P0V8_SERDES_VDDA_PEX2")
		)
		(pad "2" smd rect
			(at -0.2667 0 90)
			(size 0.3048 0.381)
			(layers "B.Cu" "B.Mask" "B.Paste")
			(net "GND")
		)
	)
	(footprint ""
		(layer "B.Cu")
		(at 234.979972 -350.370394 180)
		(property "Reference" "PR7153"
			(at 0 0 0)
			(layer "B.SilkS")
			(hide yes)
			(effects
				(font
					(size 1.27 1.27)
				)
				(justify mirror)
			)
		)
		(property "Value" ""
			(at 0 0 0)
			(layer "B.Fab")
			(effects
				(font
					(size 1.27 1.27)
				)
				(justify mirror)
			)
		)
		(duplicate_pad_numbers_are_jumpers no)
		(fp_line
			(start 0.7874 0.4064)
			(end 0.7874 -0.4064)
			(stroke
				(width 0.1524)
				(type default)
			)
			(layer "B.SilkS")
		)
		(fp_line
			(start 0.7874 -0.4064)
			(end -0.7874 -0.4064)
			(stroke
				(width 0.1524)
				(type default)
			)
			(layer "B.SilkS")
		)
		(fp_line
			(start -0.7874 0.4064)
			(end 0.7874 0.4064)
			(stroke
				(width 0.1524)
				(type default)
			)
			(layer "B.SilkS")
		)
		(fp_line
			(start -0.7874 -0.4064)
			(end -0.7874 0.4064)
			(stroke
				(width 0.1524)
				(type default)
			)
			(layer "B.SilkS")
		)
		(fp_line
			(start 0.67945 0.3048)
			(end 0.67945 -0.305054)
			(stroke
				(width 0.1)
				(type default)
			)
			(layer "B.Fab")
		)
		(fp_line
			(start 0.67945 -0.305054)
			(end 0.12065 -0.305054)
			(stroke
				(width 0.1)
				(type default)
			)
			(layer "B.Fab")
		)
		(fp_line
			(start 0.12065 0.3048)
			(end 0.67945 0.3048)
			(stroke
				(width 0.1)
				(type default)
			)
			(layer "B.Fab")
		)
		(fp_line
			(start 0.12065 0.2794)
			(end 0.12065 0.3048)
			(stroke
				(width 0.1)
				(type default)
			)
			(layer "B.Fab")
		)
		(fp_line
			(start 0.12065 -0.2794)
			(end -0.12065 -0.2794)
			(stroke
				(width 0.1)
				(type default)
			)
			(layer "B.Fab")
		)
		(fp_line
			(start 0.12065 -0.305054)
			(end 0.12065 -0.2794)
			(stroke
				(width 0.1)
				(type default)
			)
			(layer "B.Fab")
		)
		(fp_line
			(start -0.120396 0.3048)
			(end -0.120396 0.2794)
			(stroke
				(width 0.1)
				(type default)
			)
			(layer "B.Fab")
		)
		(fp_line
			(start -0.120396 0.2794)
			(end 0.12065 0.2794)
			(stroke
				(width 0.1)
				(type default)
			)
			(layer "B.Fab")
		)
		(fp_line
			(start -0.12065 -0.2794)
			(end -0.12065 -0.3048)
			(stroke
				(width 0.1)
				(type default)
			)
			(layer "B.Fab")
		)
		(fp_line
			(start -0.12065 -0.3048)
			(end -0.67945 -0.3048)
			(stroke
				(width 0.1)
				(type default)
			)
			(layer "B.Fab")
		)
		(fp_line
			(start -0.67945 0.3048)
			(end -0.120396 0.3048)
			(stroke
				(width 0.1)
				(type default)
			)
			(layer "B.Fab")
		)
		(fp_line
			(start -0.67945 -0.3048)
			(end -0.67945 0.3048)
			(stroke
				(width 0.1)
				(type default)
			)
			(layer "B.Fab")
		)
		(pad "1" smd circle
			(at 0.40005 0)
			(size 0 0)
			(layers "B.Cu" "B.Mask" "B.Paste")
			(net "P12V_HSC_SENSE2_P")
		)
		(pad "2" smd circle
			(at -0.40005 0)
			(size 0 0)
			(layers "B.Cu" "B.Mask" "B.Paste")
			(net "P12V_HSC_SENSE2_R1_P")
		)
	)
	(footprint ""
		(layer "B.Cu")
		(at 74.026776 -299.2247 90)
		(property "Reference" "R1245"
			(at 0 0 90)
			(layer "B.SilkS")
			(hide yes)
			(effects
				(font
					(size 1.27 1.27)
				)
				(justify mirror)
			)
		)
		(property "Value" ""
			(at 0 0 90)
			(layer "B.Fab")
			(effects
				(font
					(size 1.27 1.27)
				)
				(justify mirror)
			)
		)
		(duplicate_pad_numbers_are_jumpers no)
		(fp_line
			(start 0.7874 -0.4064)
			(end -0.7874 -0.4064)
			(stroke
				(width 0.1524)
				(type default)
			)
			(layer "B.SilkS")
		)
		(fp_line
			(start -0.7874 -0.4064)
			(end -0.7874 0.4064)
			(stroke
				(width 0.1524)
				(type default)
			)
			(layer "B.SilkS")
		)
		(fp_line
			(start 0.7874 0.4064)
			(end 0.7874 -0.4064)
			(stroke
				(width 0.1524)
				(type default)
			)
			(layer "B.SilkS")
		)
		(fp_line
			(start -0.7874 0.4064)
			(end 0.7874 0.4064)
			(stroke
				(width 0.1524)
				(type default)
			)
			(layer "B.SilkS")
		)
		(fp_line
			(start 0.67945 -0.305054)
			(end 0.12065 -0.305054)
			(stroke
				(width 0.1)
				(type default)
			)
			(layer "B.Fab")
		)
		(fp_line
			(start 0.12065 -0.305054)
			(end 0.12065 -0.2794)
			(stroke
				(width 0.1)
				(type default)
			)
			(layer "B.Fab")
		)
		(fp_line
			(start -0.12065 -0.3048)
			(end -0.67945 -0.3048)
			(stroke
				(width 0.1)
				(type default)
			)
			(layer "B.Fab")
		)
		(fp_line
			(start -0.67945 -0.3048)
			(end -0.67945 0.3048)
			(stroke
				(width 0.1)
				(type default)
			)
			(layer "B.Fab")
		)
		(fp_line
			(start 0.12065 -0.2794)
			(end -0.12065 -0.2794)
			(stroke
				(width 0.1)
				(type default)
			)
			(layer "B.Fab")
		)
		(fp_line
			(start -0.12065 -0.2794)
			(end -0.12065 -0.3048)
			(stroke
				(width 0.1)
				(type default)
			)
			(layer "B.Fab")
		)
		(fp_line
			(start 0.12065 0.2794)
			(end 0.12065 0.3048)
			(stroke
				(width 0.1)
				(type default)
			)
			(layer "B.Fab")
		)
		(fp_line
			(start -0.120396 0.2794)
			(end 0.12065 0.2794)
			(stroke
				(width 0.1)
				(type default)
			)
			(layer "B.Fab")
		)
		(fp_line
			(start 0.67945 0.3048)
			(end 0.67945 -0.305054)
			(stroke
				(width 0.1)
				(type default)
			)
			(layer "B.Fab")
		)
		(fp_line
			(start 0.12065 0.3048)
			(end 0.67945 0.3048)
			(stroke
				(width 0.1)
				(type default)
			)
			(layer "B.Fab")
		)
		(fp_line
			(start -0.120396 0.3048)
			(end -0.120396 0.2794)
			(stroke
				(width 0.1)
				(type default)
			)
			(layer "B.Fab")
		)
		(fp_line
			(start -0.67945 0.3048)
			(end -0.120396 0.3048)
			(stroke
				(width 0.1)
				(type default)
			)
			(layer "B.Fab")
		)
		(pad "1" smd circle
			(at 0.40005 0 270)
			(size 0 0)
			(layers "B.Cu" "B.Mask" "B.Paste")
			(net "PEX0_ADCTEMP_VINP1")
		)
		(pad "2" smd circle
			(at -0.40005 0 270)
			(size 0 0)
			(layers "B.Cu" "B.Mask" "B.Paste")
			(net "GND")
		)
	)
	(footprint ""
		(layer "B.Cu")
		(at 181.4703 -296.37482)
		(property "Reference" "C1375"
			(at 0 0 0)
			(layer "B.SilkS")
			(hide yes)
			(effects
				(font
					(size 1.27 1.27)
				)
				(justify mirror)
			)
		)
		(property "Value" ""
			(at 0 0 0)
			(layer "B.Fab")
			(effects
				(font
					(size 1.27 1.27)
				)
				(justify mirror)
			)
		)
		(duplicate_pad_numbers_are_jumpers no)
		(fp_line
			(start -0.299974 -0.150114)
			(end -0.299974 0.150114)
			(stroke
				(width 0.1)
				(type default)
			)
			(layer "B.Fab")
		)
		(fp_line
			(start -0.299974 0.150114)
			(end 0.299974 0.150114)
			(stroke
				(width 0.1)
				(type default)
			)
			(layer "B.Fab")
		)
		(fp_line
			(start 0.299974 -0.150114)
			(end -0.299974 -0.150114)
			(stroke
				(width 0.1)
				(type default)
			)
			(layer "B.Fab")
		)
		(fp_line
			(start 0.299974 0.150114)
			(end 0.299974 -0.150114)
			(stroke
				(width 0.1)
				(type default)
			)
			(layer "B.Fab")
		)
		(pad "1" smd rect
			(at 0.2667 0 180)
			(size 0.3048 0.381)
			(layers "B.Cu" "B.Mask" "B.Paste")
			(net "P0V8_PEX1")
		)
		(pad "2" smd rect
			(at -0.2667 0 180)
			(size 0.3048 0.381)
			(layers "B.Cu" "B.Mask" "B.Paste")
			(net "GND")
		)
	)
	(footprint ""
		(layer "B.Cu")
		(at 121.437146 -325.186294 -90)
		(property "Reference" "C4270"
			(at 0 0 90)
			(layer "B.SilkS")
			(hide yes)
			(effects
				(font
					(size 1.27 1.27)
				)
				(justify mirror)
			)
		)
		(property "Value" ""
			(at 0 0 90)
			(layer "B.Fab")
			(effects
				(font
					(size 1.27 1.27)
				)
				(justify mirror)
			)
		)
		(duplicate_pad_numbers_are_jumpers no)
		(fp_line
			(start -1.2954 0.5842)
			(end 1.2954 0.5842)
			(stroke
				(width 0.1524)
				(type default)
			)
			(layer "B.SilkS")
		)
		(fp_line
			(start 1.2954 0.5842)
			(end 1.2954 -0.5842)
			(stroke
				(width 0.1524)
				(type default)
			)
			(layer "B.SilkS")
		)
		(fp_line
			(start -1.2954 -0.5842)
			(end -1.2954 0.5842)
			(stroke
				(width 0.1524)
				(type default)
			)
			(layer "B.SilkS")
		)
		(fp_line
			(start 1.2954 -0.5842)
			(end -1.2954 -0.5842)
			(stroke
				(width 0.1524)
				(type default)
			)
			(layer "B.SilkS")
		)
		(fp_line
			(start -0.8636 0.4572)
			(end 0.8636 0.4572)
			(stroke
				(width 0.1)
				(type default)
			)
			(layer "B.Fab")
		)
		(fp_line
			(start 0.8636 0.4572)
			(end 0.8636 0.4064)
			(stroke
				(width 0.1)
				(type default)
			)
			(layer "B.Fab")
		)
		(fp_line
			(start -1.1938 0.4064)
			(end -0.8636 0.4064)
			(stroke
				(width 0.1)
				(type default)
			)
			(layer "B.Fab")
		)
		(fp_line
			(start -0.8636 0.4064)
			(end -0.8636 0.4572)
			(stroke
				(width 0.1)
				(type default)
			)
			(layer "B.Fab")
		)
		(fp_line
			(start 0.8636 0.4064)
			(end 1.1938 0.4064)
			(stroke
				(width 0.1)
				(type default)
			)
			(layer "B.Fab")
		)
		(fp_line
			(start 1.1938 0.4064)
			(end 1.1938 -0.4064)
			(stroke
				(width 0.1)
				(type default)
			)
			(layer "B.Fab")
		)
		(fp_line
			(start -1.1938 -0.4064)
			(end -1.1938 0.4064)
			(stroke
				(width 0.1)
				(type default)
			)
			(layer "B.Fab")
		)
		(fp_line
			(start -0.8636 -0.4064)
			(end -1.1938 -0.4064)
			(stroke
				(width 0.1)
				(type default)
			)
			(layer "B.Fab")
		)
		(fp_line
			(start 0.8636 -0.4064)
			(end 0.8636 -0.4572)
			(stroke
				(width 0.1)
				(type default)
			)
			(layer "B.Fab")
		)
		(fp_line
			(start 1.1938 -0.4064)
			(end 0.8636 -0.4064)
			(stroke
				(width 0.1)
				(type default)
			)
			(layer "B.Fab")
		)
		(fp_line
			(start -0.8636 -0.4572)
			(end -0.8636 -0.4064)
			(stroke
				(width 0.1)
				(type default)
			)
			(layer "B.Fab")
		)
		(fp_line
			(start 0.8636 -0.4572)
			(end -0.8636 -0.4572)
			(stroke
				(width 0.1)
				(type default)
			)
			(layer "B.Fab")
		)
		(pad "1" smd rect
			(at 0.7366 0 180)
			(size 0.7112 0.8128)
			(layers "B.Cu" "B.Mask" "B.Paste")
			(net "P0V8_SERDES_VDDA_PEX1_C8")
		)
		(pad "2" smd rect
			(at -0.7366 0 180)
			(size 0.7112 0.8128)
			(layers "B.Cu" "B.Mask" "B.Paste")
			(net "GND")
		)
	)
	(footprint ""
		(layer "B.Cu")
		(at 40.05707 -291.72662 180)
		(property "Reference" "R3293"
			(at 0 0 0)
			(layer "B.SilkS")
			(hide yes)
			(effects
				(font
					(size 1.27 1.27)
				)
				(justify mirror)
			)
		)
		(property "Value" ""
			(at 0 0 0)
			(layer "B.Fab")
			(effects
				(font
					(size 1.27 1.27)
				)
				(justify mirror)
			)
		)
		(duplicate_pad_numbers_are_jumpers no)
		(fp_line
			(start 0.7874 0.4064)
			(end 0.7874 -0.4064)
			(stroke
				(width 0.1524)
				(type default)
			)
			(layer "B.SilkS")
		)
		(fp_line
			(start 0.7874 -0.4064)
			(end -0.7874 -0.4064)
			(stroke
				(width 0.1524)
				(type default)
			)
			(layer "B.SilkS")
		)
		(fp_line
			(start -0.7874 0.4064)
			(end 0.7874 0.4064)
			(stroke
				(width 0.1524)
				(type default)
			)
			(layer "B.SilkS")
		)
		(fp_line
			(start -0.7874 -0.4064)
			(end -0.7874 0.4064)
			(stroke
				(width 0.1524)
				(type default)
			)
			(layer "B.SilkS")
		)
		(fp_line
			(start 0.67945 0.3048)
			(end 0.67945 -0.305054)
			(stroke
				(width 0.1)
				(type default)
			)
			(layer "B.Fab")
		)
		(fp_line
			(start 0.67945 -0.305054)
			(end 0.12065 -0.305054)
			(stroke
				(width 0.1)
				(type default)
			)
			(layer "B.Fab")
		)
		(fp_line
			(start 0.12065 0.3048)
			(end 0.67945 0.3048)
			(stroke
				(width 0.1)
				(type default)
			)
			(layer "B.Fab")
		)
		(fp_line
			(start 0.12065 0.2794)
			(end 0.12065 0.3048)
			(stroke
				(width 0.1)
				(type default)
			)
			(layer "B.Fab")
		)
		(fp_line
			(start 0.12065 -0.2794)
			(end -0.12065 -0.2794)
			(stroke
				(width 0.1)
				(type default)
			)
			(layer "B.Fab")
		)
		(fp_line
			(start 0.12065 -0.305054)
			(end 0.12065 -0.2794)
			(stroke
				(width 0.1)
				(type default)
			)
			(layer "B.Fab")
		)
		(fp_line
			(start -0.120396 0.3048)
			(end -0.120396 0.2794)
			(stroke
				(width 0.1)
				(type default)
			)
			(layer "B.Fab")
		)
		(fp_line
			(start -0.120396 0.2794)
			(end 0.12065 0.2794)
			(stroke
				(width 0.1)
				(type default)
			)
			(layer "B.Fab")
		)
		(fp_line
			(start -0.12065 -0.2794)
			(end -0.12065 -0.3048)
			(stroke
				(width 0.1)
				(type default)
			)
			(layer "B.Fab")
		)
		(fp_line
			(start -0.12065 -0.3048)
			(end -0.67945 -0.3048)
			(stroke
				(width 0.1)
				(type default)
			)
			(layer "B.Fab")
		)
		(fp_line
			(start -0.67945 0.3048)
			(end -0.120396 0.3048)
			(stroke
				(width 0.1)
				(type default)
			)
			(layer "B.Fab")
		)
		(fp_line
			(start -0.67945 -0.3048)
			(end -0.67945 0.3048)
			(stroke
				(width 0.1)
				(type default)
			)
			(layer "B.Fab")
		)
		(pad "1" smd circle
			(at 0.40005 0)
			(size 0 0)
			(layers "B.Cu" "B.Mask" "B.Paste")
			(net "SPI_PEX0_CLK_R")
		)
		(pad "2" smd circle
			(at -0.40005 0)
			(size 0 0)
			(layers "B.Cu" "B.Mask" "B.Paste")
			(net "SPI_PEX0_CLK")
		)
	)
	(footprint ""
		(layer "B.Cu")
		(at 406.049988 -301.599854 -90)
		(property "Reference" "C1999"
			(at 0 0 90)
			(layer "B.SilkS")
			(hide yes)
			(effects
				(font
					(size 1.27 1.27)
				)
				(justify mirror)
			)
		)
		(property "Value" ""
			(at 0 0 90)
			(layer "B.Fab")
			(effects
				(font
					(size 1.27 1.27)
				)
				(justify mirror)
			)
		)
		(duplicate_pad_numbers_are_jumpers no)
		(fp_line
			(start -0.299974 0.150114)
			(end 0.299974 0.150114)
			(stroke
				(width 0.1)
				(type default)
			)
			(layer "B.Fab")
		)
		(fp_line
			(start 0.299974 0.150114)
			(end 0.299974 -0.150114)
			(stroke
				(width 0.1)
				(type default)
			)
			(layer "B.Fab")
		)
		(fp_line
			(start -0.299974 -0.150114)
			(end -0.299974 0.150114)
			(stroke
				(width 0.1)
				(type default)
			)
			(layer "B.Fab")
		)
		(fp_line
			(start 0.299974 -0.150114)
			(end -0.299974 -0.150114)
			(stroke
				(width 0.1)
				(type default)
			)
			(layer "B.Fab")
		)
		(pad "1" smd rect
			(at 0.2667 0 90)
			(size 0.3048 0.381)
			(layers "B.Cu" "B.Mask" "B.Paste")
			(net "P0V8_SERDES_VDDA_PEX3")
		)
		(pad "2" smd rect
			(at -0.2667 0 90)
			(size 0.3048 0.381)
			(layers "B.Cu" "B.Mask" "B.Paste")
			(net "GND")
		)
	)
	(footprint ""
		(layer "B.Cu")
		(at 405.100028 -288.299906 90)
		(property "Reference" "C3463"
			(at 0 0 90)
			(layer "B.SilkS")
			(hide yes)
			(effects
				(font
					(size 1.27 1.27)
				)
				(justify mirror)
			)
		)
		(property "Value" ""
			(at 0 0 90)
			(layer "B.Fab")
			(effects
				(font
					(size 1.27 1.27)
				)
				(justify mirror)
			)
		)
		(duplicate_pad_numbers_are_jumpers no)
		(fp_line
			(start 0.299974 -0.150114)
			(end -0.299974 -0.150114)
			(stroke
				(width 0.1)
				(type default)
			)
			(layer "B.Fab")
		)
		(fp_line
			(start -0.299974 -0.150114)
			(end -0.299974 0.150114)
			(stroke
				(width 0.1)
				(type default)
			)
			(layer "B.Fab")
		)
		(fp_line
			(start 0.299974 0.150114)
			(end 0.299974 -0.150114)
			(stroke
				(width 0.1)
				(type default)
			)
			(layer "B.Fab")
		)
		(fp_line
			(start -0.299974 0.150114)
			(end 0.299974 0.150114)
			(stroke
				(width 0.1)
				(type default)
			)
			(layer "B.Fab")
		)
		(pad "1" smd rect
			(at 0.2667 0 270)
			(size 0.3048 0.381)
			(layers "B.Cu" "B.Mask" "B.Paste")
			(net "P1V25_PEX3")
		)
		(pad "2" smd rect
			(at -0.2667 0 270)
			(size 0.3048 0.381)
			(layers "B.Cu" "B.Mask" "B.Paste")
			(net "GND")
		)
	)
)
